# T6G (Grand Teton) — schematic netlist excerpt (pin names and nets, part order shuffled) for the footprints in the layout excerpt that follows; sources: Cadence DE-HDL packaged netlist, KiCad conversion of 04192023_DAF0TMB3IC0_F0TG_MB_C_brd_V02_OCP.brd

R9  Q_RES  0 5% CHIP  pkg 0402LF  page 85 : A = JTAG_PLD_TDI ; B = JTAG_SCM_PLD_TDI
R394  Q_RES  2.2K 5% CHIP  pkg 0402LF  page 27 : A = CPU0_SA1 ; B = GND
C433  Q_CAP  100UF 4V 20% X6S  pkg C0805  page 356 : A = P1V8_CPU1_RT3_1A ; B = GND

(kicad_pcb
	(version 20260206)
	(generator "pcbnew")
	(generator_version "10.0")
	(general
		(thickness 1.6)
		(legacy_teardrops no)
	)
	(paper "A4")
	(title_block
		(title "04192023_DAF0TMB3IC0_F0TG_MB_C_brd_V02_OCP.brd")
		(comment 1 "Grand Teton / footprints 7137-7139 of 8354")
	)
	(layers
		(0 "F.Cu" signal "TOP")
		(4 "In1.Cu" signal "GND")
		(6 "In2.Cu" signal "IN1")
		(8 "In3.Cu" signal "GND1")
		(10 "In4.Cu" signal "IN2")
		(12 "In5.Cu" signal "GND2")
		(14 "In6.Cu" signal "IN3")
		(16 "In7.Cu" signal "GND3")
		(18 "In8.Cu" signal "VCC")
		(20 "In9.Cu" signal "VCC1")
		(22 "In10.Cu" signal "GND4")
		(24 "In11.Cu" signal "IN4")
		(26 "In12.Cu" signal "GND5")
		(28 "In13.Cu" signal "IN5")
		(30 "In14.Cu" signal "GND6")
		(32 "In15.Cu" signal "IN6")
		(34 "In16.Cu" signal "GND7")
		(2 "B.Cu" signal "BOTTOM")
		(9 "F.Adhes" user "F.Adhesive")
		(11 "B.Adhes" user "B.Adhesive")
		(13 "F.Paste" user "Package Geometry/Pastemask Top")
		(15 "B.Paste" user "Package Geometry/Pastemask Bottom")
		(5 "F.SilkS" user "Ref Des/Silkscreen Top")
		(7 "B.SilkS" user "Ref Des/Silkscreen Bottom")
		(1 "F.Mask" user "Board Geometry/Soldermask Top")
		(3 "B.Mask" user "Board Geometry/Soldermask Bottom")
		(17 "Dwgs.User" user "User.Drawings")
		(19 "Cmts.User" user "User.Comments")
		(21 "Eco1.User" user "User.Eco1")
		(23 "Eco2.User" user "User.Eco2")
		(25 "Edge.Cuts" user "Board Geometry/Outline")
		(27 "Margin" user)
		(31 "F.CrtYd" user "Package Geometry/Place Bound Top")
		(29 "B.CrtYd" user "Package Geometry/Place Bound Bottom")
		(35 "F.Fab" user "Ref Des/Assembly Top")
		(33 "B.Fab" user "Ref Des/Assembly Bottom")
	)
	(footprint ""
		(layer "B.Cu")
		(at 337.687158 -309.214012 -90)
		(property "Reference" "R394"
			(at 0 0 90)
			(layer "B.SilkS")
			(hide yes)
			(effects
				(font
					(size 1.27 1.27)
				)
				(justify mirror)
			)
		)
		(property "Value" ""
			(at 0 0 90)
			(layer "B.Fab")
			(effects
				(font
					(size 1.27 1.27)
				)
				(justify mirror)
			)
		)
		(duplicate_pad_numbers_are_jumpers no)
		(fp_line
			(start -0.7874 0.4064)
			(end 0.7874 0.4064)
			(stroke
				(width 0.1524)
				(type default)
			)
			(layer "B.SilkS")
		)
		(fp_line
			(start 0.7874 0.4064)
			(end 0.7874 -0.4064)
			(stroke
				(width 0.1524)
				(type default)
			)
			(layer "B.SilkS")
		)
		(fp_line
			(start -0.7874 -0.4064)
			(end -0.7874 0.4064)
			(stroke
				(width 0.1524)
				(type default)
			)
			(layer "B.SilkS")
		)
		(fp_line
			(start 0.7874 -0.4064)
			(end -0.7874 -0.4064)
			(stroke
				(width 0.1524)
				(type default)
			)
			(layer "B.SilkS")
		)
		(fp_line
			(start -0.67945 0.3048)
			(end -0.120396 0.3048)
			(stroke
				(width 0.1)
				(type default)
			)
			(layer "B.Fab")
		)
		(fp_line
			(start -0.120396 0.3048)
			(end -0.120396 0.2794)
			(stroke
				(width 0.1)
				(type default)
			)
			(layer "B.Fab")
		)
		(fp_line
			(start 0.12065 0.3048)
			(end 0.67945 0.3048)
			(stroke
				(width 0.1)
				(type default)
			)
			(layer "B.Fab")
		)
		(fp_line
			(start 0.67945 0.3048)
			(end 0.67945 -0.305054)
			(stroke
				(width 0.1)
				(type default)
			)
			(layer "B.Fab")
		)
		(fp_line
			(start -0.120396 0.2794)
			(end 0.12065 0.2794)
			(stroke
				(width 0.1)
				(type default)
			)
			(layer "B.Fab")
		)
		(fp_line
			(start 0.12065 0.2794)
			(end 0.12065 0.3048)
			(stroke
				(width 0.1)
				(type default)
			)
			(layer "B.Fab")
		)
		(fp_line
			(start -0.12065 -0.2794)
			(end -0.12065 -0.3048)
			(stroke
				(width 0.1)
				(type default)
			)
			(layer "B.Fab")
		)
		(fp_line
			(start 0.12065 -0.2794)
			(end -0.12065 -0.2794)
			(stroke
				(width 0.1)
				(type default)
			)
			(layer "B.Fab")
		)
		(fp_line
			(start -0.67945 -0.3048)
			(end -0.67945 0.3048)
			(stroke
				(width 0.1)
				(type default)
			)
			(layer "B.Fab")
		)
		(fp_line
			(start -0.12065 -0.3048)
			(end -0.67945 -0.3048)
			(stroke
				(width 0.1)
				(type default)
			)
			(layer "B.Fab")
		)
		(fp_line
			(start 0.12065 -0.305054)
			(end 0.12065 -0.2794)
			(stroke
				(width 0.1)
				(type default)
			)
			(layer "B.Fab")
		)
		(fp_line
			(start 0.67945 -0.305054)
			(end 0.12065 -0.305054)
			(stroke
				(width 0.1)
				(type default)
			)
			(layer "B.Fab")
		)
		(pad "1" smd circle
			(at 0.40005 0 90)
			(size 0 0)
			(layers "B.Cu" "B.Mask" "B.Paste")
			(net "CPU0_SA1")
		)
		(pad "2" smd circle
			(at -0.40005 0 90)
			(size 0 0)
			(layers "B.Cu" "B.Mask" "B.Paste")
			(net "GND")
		)
	)
	(footprint ""
		(layer "B.Cu")
		(at 136.016238 -387.084062 -90)
		(property "Reference" "C433"
			(at 0 0 90)
			(layer "B.SilkS")
			(hide yes)
			(effects
				(font
					(size 1.27 1.27)
				)
				(justify mirror)
			)
		)
		(property "Value" ""
			(at 0 0 90)
			(layer "B.Fab")
			(effects
				(font
					(size 1.27 1.27)
				)
				(justify mirror)
			)
		)
		(duplicate_pad_numbers_are_jumpers no)
		(fp_line
			(start -1.524 0.762)
			(end 1.524 0.762)
			(stroke
				(width 0.1524)
				(type default)
			)
			(layer "B.SilkS")
		)
		(fp_line
			(start 1.524 0.762)
			(end 1.524 -0.762)
			(stroke
				(width 0.1524)
				(type default)
			)
			(layer "B.SilkS")
		)
		(fp_line
			(start -1.524 -0.762)
			(end -1.524 0.762)
			(stroke
				(width 0.1524)
				(type default)
			)
			(layer "B.SilkS")
		)
		(fp_line
			(start 1.524 -0.762)
			(end -1.524 -0.762)
			(stroke
				(width 0.1524)
				(type default)
			)
			(layer "B.SilkS")
		)
		(fp_line
			(start -1.1049 0.724916)
			(end -1.1049 -0.724916)
			(stroke
				(width 0.1)
				(type default)
			)
			(layer "B.Fab")
		)
		(fp_line
			(start 1.1049 0.724916)
			(end -1.1049 0.724916)
			(stroke
				(width 0.1)
				(type default)
			)
			(layer "B.Fab")
		)
		(fp_line
			(start -1.1049 -0.724916)
			(end 1.1049 -0.724916)
			(stroke
				(width 0.1)
				(type default)
			)
			(layer "B.Fab")
		)
		(fp_line
			(start 1.1049 -0.724916)
			(end 1.1049 0.724916)
			(stroke
				(width 0.1)
				(type default)
			)
			(layer "B.Fab")
		)
		(pad "1" smd rect
			(at 0.889 0 270)
			(size 1.016 1.27)
			(layers "B.Cu" "B.Mask" "B.Paste")
			(net "P1V8_CPU1_RT3_1A")
		)
		(pad "2" smd rect
			(at -0.889 0 270)
			(size 1.016 1.27)
			(layers "B.Cu" "B.Mask" "B.Paste")
			(net "GND")
		)
	)
	(footprint ""
		(layer "B.Cu")
		(at 166.955216 -112.902238 180)
		(property "Reference" "R9"
			(at 0 0 0)
			(layer "B.SilkS")
			(hide yes)
			(effects
				(font
					(size 1.27 1.27)
				)
				(justify mirror)
			)
		)
		(property "Value" ""
			(at 0 0 0)
			(layer "B.Fab")
			(effects
				(font
					(size 1.27 1.27)
				)
				(justify mirror)
			)
		)
		(duplicate_pad_numbers_are_jumpers no)
		(fp_line
			(start 0.7874 0.4064)
			(end 0.7874 -0.4064)
			(stroke
				(width 0.1524)
				(type default)
			)
			(layer "B.SilkS")
		)
		(fp_line
			(start 0.7874 -0.4064)
			(end -0.7874 -0.4064)
			(stroke
				(width 0.1524)
				(type default)
			)
			(layer "B.SilkS")
		)
		(fp_line
			(start -0.7874 0.4064)
			(end 0.7874 0.4064)
			(stroke
				(width 0.1524)
				(type default)
			)
			(layer "B.SilkS")
		)
		(fp_line
			(start -0.7874 -0.4064)
			(end -0.7874 0.4064)
			(stroke
				(width 0.1524)
				(type default)
			)
			(layer "B.SilkS")
		)
		(fp_line
			(start 0.67945 0.3048)
			(end 0.67945 -0.305054)
			(stroke
				(width 0.1)
				(type default)
			)
			(layer "B.Fab")
		)
		(fp_line
			(start 0.67945 -0.305054)
			(end 0.12065 -0.305054)
			(stroke
				(width 0.1)
				(type default)
			)
			(layer "B.Fab")
		)
		(fp_line
			(start 0.12065 0.3048)
			(end 0.67945 0.3048)
			(stroke
				(width 0.1)
				(type default)
			)
			(layer "B.Fab")
		)
		(fp_line
			(start 0.12065 0.2794)
			(end 0.12065 0.3048)
			(stroke
				(width 0.1)
				(type default)
			)
			(layer "B.Fab")
		)
		(fp_line
			(start 0.12065 -0.2794)
			(end -0.12065 -0.2794)
			(stroke
				(width 0.1)
				(type default)
			)
			(layer "B.Fab")
		)
		(fp_line
			(start 0.12065 -0.305054)
			(end 0.12065 -0.2794)
			(stroke
				(width 0.1)
				(type default)
			)
			(layer "B.Fab")
		)
		(fp_line
			(start -0.120396 0.3048)
			(end -0.120396 0.2794)
			(stroke
				(width 0.1)
				(type default)
			)
			(layer "B.Fab")
		)
		(fp_line
			(start -0.120396 0.2794)
			(end 0.12065 0.2794)
			(stroke
				(width 0.1)
				(type default)
			)
			(layer "B.Fab")
		)
		(fp_line
			(start -0.12065 -0.2794)
			(end -0.12065 -0.3048)
			(stroke
				(width 0.1)
				(type default)
			)
			(layer "B.Fab")
		)
		(fp_line
			(start -0.12065 -0.3048)
			(end -0.67945 -0.3048)
			(stroke
				(width 0.1)
				(type default)
			)
			(layer "B.Fab")
		)
		(fp_line
			(start -0.67945 0.3048)
			(end -0.120396 0.3048)
			(stroke
				(width 0.1)
				(type default)
			)
			(layer "B.Fab")
		)
		(fp_line
			(start -0.67945 -0.3048)
			(end -0.67945 0.3048)
			(stroke
				(width 0.1)
				(type default)
			)
			(layer "B.Fab")
		)
		(pad "1" smd circle
			(at 0.40005 0)
			(size 0 0)
			(layers "B.Cu" "B.Mask" "B.Paste")
			(net "JTAG_PLD_TDI")
		)
		(pad "2" smd circle
			(at -0.40005 0)
			(size 0 0)
			(layers "B.Cu" "B.Mask" "B.Paste")
			(net "JTAG_SCM_PLD_TDI")
		)
	)
)
